# ZAIUS-LBB-EVT2-X01-BOM-X03-20161116.xls — TLA (bom)
| FOXCONN TECHNOLOGY GROUP |  |  |  |  |  |  |  |  |  |
| BILL OF MATERIAL |  |  |  |  |  |  |  |  |  |
| AA P/N | 1A42HHD00-600-G | CUSTOMER |  | Customer P/N |  | Product Code |  |  |  |
| PWA P/N |  | PWA DESCRIPTION | P9 LUNCH BOX BOARD_G |  |  | PWA REV |  | Prepared By SE |  |
| Item | FOXCONN P/N | Dell P/N | Part Description | Manufacturer  Full Name | Manufacturer  Part Number | Qty | RoHS Status | Location | Remark |
| 1 | 7J-004-938 |  | L6 LABEL ( 12.7*11.1mm) | FOXCONN / EPD1 | 7J-004-938 | 1 | G |  |  |
| 3 | 2A582N700-600-G |  | Screw M3X7 | JINFUYUN | 2A582N700-600-G | 4 | G |  | Rev:A For PSU Power connector. EPD5 contact window: <name> |
| 4 | 2A3400Y00-600-G |  | Nut M3. | HONGYIJIN | 2A3400Y00-600-G | 4 | G |  | Rev:X01 For PSU Power connector. EPD5 contact window: <name> |
